(kicad_pcb
	(version 20260206)
	(generator "pcbnew")
	(generator_version "10.0")
	(general
		(thickness 1.6)
		(legacy_teardrops no)
	)
	(paper "A4")
	(title_block
		(title "03242023_DA0F0TMBIJ0_F0T_Motherboard_J_brd_V01_OCP.brd")
		(comment 1 "Grand Teton / footprints 4831-4837 of 6105")
	)
	(layers
		(0 "F.Cu" signal "TOP")
		(4 "In1.Cu" signal "GND")
		(6 "In2.Cu" signal "IN1")
		(8 "In3.Cu" signal "GND1")
		(10 "In4.Cu" signal "IN2")
		(12 "In5.Cu" signal "GND2")
		(14 "In6.Cu" signal "IN3")
		(16 "In7.Cu" signal "GND3")
		(18 "In8.Cu" signal "VCC")
		(20 "In9.Cu" signal "VCC1")
		(22 "In10.Cu" signal "GND4")
		(24 "In11.Cu" signal "IN4")
		(26 "In12.Cu" signal "GND5")
		(28 "In13.Cu" signal "IN5")
		(30 "In14.Cu" signal "GND6")
		(32 "In15.Cu" signal "IN6")
		(34 "In16.Cu" signal "GND7")
		(2 "B.Cu" signal "BOTTOM")
		(9 "F.Adhes" user "F.Adhesive")
		(11 "B.Adhes" user "B.Adhesive")
		(13 "F.Paste" user "Package Geometry/Pastemask Top")
		(15 "B.Paste" user "Package Geometry/Pastemask Bottom")
		(5 "F.SilkS" user "Ref Des/Silkscreen Top")
		(7 "B.SilkS" user "Ref Des/Silkscreen Bottom")
		(1 "F.Mask" user "Board Geometry/Soldermask Top")
		(3 "B.Mask" user "Board Geometry/Soldermask Bottom")
		(17 "Dwgs.User" user "User.Drawings")
		(19 "Cmts.User" user "User.Comments")
		(21 "Eco1.User" user "User.Eco1")
		(23 "Eco2.User" user "User.Eco2")
		(25 "Edge.Cuts" user "Board Geometry/Outline")
		(27 "Margin" user)
		(31 "F.CrtYd" user "Package Geometry/Place Bound Top")
		(29 "B.CrtYd" user "Package Geometry/Place Bound Bottom")
		(35 "F.Fab" user "Ref Des/Assembly Top")
		(33 "B.Fab" user "Ref Des/Assembly Bottom")
	)
	(footprint ""
		(layer "B.Cu")
		(at 36.956238 -130.80492)
		(property "Reference" "R2571"
			(at 0 0 0)
			(layer "B.SilkS")
			(hide yes)
			(effects
				(font
					(size 1.27 1.27)
				)
				(justify mirror)
			)
		)
		(property "Value" ""
			(at 0 0 0)
			(layer "B.Fab")
			(effects
				(font
					(size 1.27 1.27)
				)
				(justify mirror)
			)
		)
		(duplicate_pad_numbers_are_jumpers no)
		(fp_line
			(start -0.7874 -0.4064)
			(end -0.7874 0.4064)
			(stroke
				(width 0.1524)
				(type default)
			)
			(layer "B.SilkS")
		)
		(fp_line
			(start -0.7874 0.4064)
			(end 0.7874 0.4064)
			(stroke
				(width 0.1524)
				(type default)
			)
			(layer "B.SilkS")
		)
		(fp_line
			(start 0.7874 -0.4064)
			(end -0.7874 -0.4064)
			(stroke
				(width 0.1524)
				(type default)
			)
			(layer "B.SilkS")
		)
		(fp_line
			(start 0.7874 0.4064)
			(end 0.7874 -0.4064)
			(stroke
				(width 0.1524)
				(type default)
			)
			(layer "B.SilkS")
		)
		(fp_line
			(start -0.67945 -0.3048)
			(end -0.67945 0.3048)
			(stroke
				(width 0.1)
				(type default)
			)
			(layer "B.Fab")
		)
		(fp_line
			(start -0.67945 0.3048)
			(end -0.120396 0.3048)
			(stroke
				(width 0.1)
				(type default)
			)
			(layer "B.Fab")
		)
		(fp_line
			(start -0.12065 -0.3048)
			(end -0.67945 -0.3048)
			(stroke
				(width 0.1)
				(type default)
			)
			(layer "B.Fab")
		)
		(fp_line
			(start -0.12065 -0.2794)
			(end -0.12065 -0.3048)
			(stroke
				(width 0.1)
				(type default)
			)
			(layer "B.Fab")
		)
		(fp_line
			(start -0.120396 0.2794)
			(end 0.12065 0.2794)
			(stroke
				(width 0.1)
				(type default)
			)
			(layer "B.Fab")
		)
		(fp_line
			(start -0.120396 0.3048)
			(end -0.120396 0.2794)
			(stroke
				(width 0.1)
				(type default)
			)
			(layer "B.Fab")
		)
		(fp_line
			(start 0.12065 -0.305054)
			(end 0.12065 -0.2794)
			(stroke
				(width 0.1)
				(type default)
			)
			(layer "B.Fab")
		)
		(fp_line
			(start 0.12065 -0.2794)
			(end -0.12065 -0.2794)
			(stroke
				(width 0.1)
				(type default)
			)
			(layer "B.Fab")
		)
		(fp_line
			(start 0.12065 0.2794)
			(end 0.12065 0.3048)
			(stroke
				(width 0.1)
				(type default)
			)
			(layer "B.Fab")
		)
		(fp_line
			(start 0.12065 0.3048)
			(end 0.67945 0.3048)
			(stroke
				(width 0.1)
				(type default)
			)
			(layer "B.Fab")
		)
		(fp_line
			(start 0.67945 -0.305054)
			(end 0.12065 -0.305054)
			(stroke
				(width 0.1)
				(type default)
			)
			(layer "B.Fab")
		)
		(fp_line
			(start 0.67945 0.3048)
			(end 0.67945 -0.305054)
			(stroke
				(width 0.1)
				(type default)
			)
			(layer "B.Fab")
		)
		(pad "1" smd circle
			(at 0.40005 0 180)
			(size 0 0)
			(layers "B.Cu" "B.Mask" "B.Paste")
			(net "P3V3_AUX")
		)
		(pad "2" smd circle
			(at -0.40005 0 180)
			(size 0 0)
			(layers "B.Cu" "B.Mask" "B.Paste")
			(net "PWRGD_PVCCFA_EHV_CPU1_R")
		)
	)
	(footprint ""
		(layer "B.Cu")
		(at 178.05019 -107.07116 180)
		(property "Reference" "R1327"
			(at 0 0 0)
			(layer "B.SilkS")
			(hide yes)
			(effects
				(font
					(size 1.27 1.27)
				)
				(justify mirror)
			)
		)
		(property "Value" ""
			(at 0 0 0)
			(layer "B.Fab")
			(effects
				(font
					(size 1.27 1.27)
				)
				(justify mirror)
			)
		)
		(duplicate_pad_numbers_are_jumpers no)
		(fp_line
			(start 0.7874 0.4064)
			(end 0.7874 -0.4064)
			(stroke
				(width 0.1524)
				(type default)
			)
			(layer "B.SilkS")
		)
		(fp_line
			(start 0.7874 -0.4064)
			(end -0.7874 -0.4064)
			(stroke
				(width 0.1524)
				(type default)
			)
			(layer "B.SilkS")
		)
		(fp_line
			(start -0.7874 0.4064)
			(end 0.7874 0.4064)
			(stroke
				(width 0.1524)
				(type default)
			)
			(layer "B.SilkS")
		)
		(fp_line
			(start -0.7874 -0.4064)
			(end -0.7874 0.4064)
			(stroke
				(width 0.1524)
				(type default)
			)
			(layer "B.SilkS")
		)
		(fp_line
			(start 0.67945 0.3048)
			(end 0.67945 -0.305054)
			(stroke
				(width 0.1)
				(type default)
			)
			(layer "B.Fab")
		)
		(fp_line
			(start 0.67945 -0.305054)
			(end 0.12065 -0.305054)
			(stroke
				(width 0.1)
				(type default)
			)
			(layer "B.Fab")
		)
		(fp_line
			(start 0.12065 0.3048)
			(end 0.67945 0.3048)
			(stroke
				(width 0.1)
				(type default)
			)
			(layer "B.Fab")
		)
		(fp_line
			(start 0.12065 0.2794)
			(end 0.12065 0.3048)
			(stroke
				(width 0.1)
				(type default)
			)
			(layer "B.Fab")
		)
		(fp_line
			(start 0.12065 -0.2794)
			(end -0.12065 -0.2794)
			(stroke
				(width 0.1)
				(type default)
			)
			(layer "B.Fab")
		)
		(fp_line
			(start 0.12065 -0.305054)
			(end 0.12065 -0.2794)
			(stroke
				(width 0.1)
				(type default)
			)
			(layer "B.Fab")
		)
		(fp_line
			(start -0.120396 0.3048)
			(end -0.120396 0.2794)
			(stroke
				(width 0.1)
				(type default)
			)
			(layer "B.Fab")
		)
		(fp_line
			(start -0.120396 0.2794)
			(end 0.12065 0.2794)
			(stroke
				(width 0.1)
				(type default)
			)
			(layer "B.Fab")
		)
		(fp_line
			(start -0.12065 -0.2794)
			(end -0.12065 -0.3048)
			(stroke
				(width 0.1)
				(type default)
			)
			(layer "B.Fab")
		)
		(fp_line
			(start -0.12065 -0.3048)
			(end -0.67945 -0.3048)
			(stroke
				(width 0.1)
				(type default)
			)
			(layer "B.Fab")
		)
		(fp_line
			(start -0.67945 0.3048)
			(end -0.120396 0.3048)
			(stroke
				(width 0.1)
				(type default)
			)
			(layer "B.Fab")
		)
		(fp_line
			(start -0.67945 -0.3048)
			(end -0.67945 0.3048)
			(stroke
				(width 0.1)
				(type default)
			)
			(layer "B.Fab")
		)
		(pad "1" smd circle
			(at 0.40005 0)
			(size 0 0)
			(layers "B.Cu" "B.Mask" "B.Paste")
			(net "PWRGD_DRAMPWRGD_CPU0_EF_R_LVC1")
		)
		(pad "2" smd circle
			(at -0.40005 0)
			(size 0 0)
			(layers "B.Cu" "B.Mask" "B.Paste")
			(net "GND")
		)
	)
	(footprint ""
		(layer "B.Cu")
		(at 81.446624 -184.096152 -90)
		(property "Reference" "R196"
			(at 0 0 90)
			(layer "B.SilkS")
			(hide yes)
			(effects
				(font
					(size 1.27 1.27)
				)
				(justify mirror)
			)
		)
		(property "Value" ""
			(at 0 0 90)
			(layer "B.Fab")
			(effects
				(font
					(size 1.27 1.27)
				)
				(justify mirror)
			)
		)
		(duplicate_pad_numbers_are_jumpers no)
		(fp_line
			(start -0.7874 0.4064)
			(end 0.7874 0.4064)
			(stroke
				(width 0.1524)
				(type default)
			)
			(layer "B.SilkS")
		)
		(fp_line
			(start 0.7874 0.4064)
			(end 0.7874 -0.4064)
			(stroke
				(width 0.1524)
				(type default)
			)
			(layer "B.SilkS")
		)
		(fp_line
			(start -0.7874 -0.4064)
			(end -0.7874 0.4064)
			(stroke
				(width 0.1524)
				(type default)
			)
			(layer "B.SilkS")
		)
		(fp_line
			(start 0.7874 -0.4064)
			(end -0.7874 -0.4064)
			(stroke
				(width 0.1524)
				(type default)
			)
			(layer "B.SilkS")
		)
		(fp_line
			(start -0.67945 0.3048)
			(end -0.120396 0.3048)
			(stroke
				(width 0.1)
				(type default)
			)
			(layer "B.Fab")
		)
		(fp_line
			(start -0.120396 0.3048)
			(end -0.120396 0.2794)
			(stroke
				(width 0.1)
				(type default)
			)
			(layer "B.Fab")
		)
		(fp_line
			(start 0.12065 0.3048)
			(end 0.67945 0.3048)
			(stroke
				(width 0.1)
				(type default)
			)
			(layer "B.Fab")
		)
		(fp_line
			(start 0.67945 0.3048)
			(end 0.67945 -0.305054)
			(stroke
				(width 0.1)
				(type default)
			)
			(layer "B.Fab")
		)
		(fp_line
			(start -0.120396 0.2794)
			(end 0.12065 0.2794)
			(stroke
				(width 0.1)
				(type default)
			)
			(layer "B.Fab")
		)
		(fp_line
			(start 0.12065 0.2794)
			(end 0.12065 0.3048)
			(stroke
				(width 0.1)
				(type default)
			)
			(layer "B.Fab")
		)
		(fp_line
			(start -0.12065 -0.2794)
			(end -0.12065 -0.3048)
			(stroke
				(width 0.1)
				(type default)
			)
			(layer "B.Fab")
		)
		(fp_line
			(start 0.12065 -0.2794)
			(end -0.12065 -0.2794)
			(stroke
				(width 0.1)
				(type default)
			)
			(layer "B.Fab")
		)
		(fp_line
			(start -0.67945 -0.3048)
			(end -0.67945 0.3048)
			(stroke
				(width 0.1)
				(type default)
			)
			(layer "B.Fab")
		)
		(fp_line
			(start -0.12065 -0.3048)
			(end -0.67945 -0.3048)
			(stroke
				(width 0.1)
				(type default)
			)
			(layer "B.Fab")
		)
		(fp_line
			(start 0.12065 -0.305054)
			(end 0.12065 -0.2794)
			(stroke
				(width 0.1)
				(type default)
			)
			(layer "B.Fab")
		)
		(fp_line
			(start 0.67945 -0.305054)
			(end 0.12065 -0.305054)
			(stroke
				(width 0.1)
				(type default)
			)
			(layer "B.Fab")
		)
		(pad "1" smd circle
			(at 0.40005 0 90)
			(size 0 0)
			(layers "B.Cu" "B.Mask" "B.Paste")
			(net "H_CPU_NMI_LVC1_N")
		)
		(pad "2" smd circle
			(at -0.40005 0 90)
			(size 0 0)
			(layers "B.Cu" "B.Mask" "B.Paste")
			(net "H_CPU1_NMI_LVC1_N")
		)
	)
	(footprint ""
		(layer "B.Cu")
		(at 449.808092 -58.325512 -90)
		(property "Reference" "PC1599"
			(at 0 0 90)
			(layer "B.SilkS")
			(hide yes)
			(effects
				(font
					(size 1.27 1.27)
				)
				(justify mirror)
			)
		)
		(property "Value" ""
			(at 0 0 90)
			(layer "B.Fab")
			(effects
				(font
					(size 1.27 1.27)
				)
				(justify mirror)
			)
		)
		(duplicate_pad_numbers_are_jumpers no)
		(fp_line
			(start -1.524 0.762)
			(end 1.524 0.762)
			(stroke
				(width 0.1524)
				(type default)
			)
			(layer "B.SilkS")
		)
		(fp_line
			(start 1.524 0.762)
			(end 1.524 -0.762)
			(stroke
				(width 0.1524)
				(type default)
			)
			(layer "B.SilkS")
		)
		(fp_line
			(start -1.524 -0.762)
			(end -1.524 0.762)
			(stroke
				(width 0.1524)
				(type default)
			)
			(layer "B.SilkS")
		)
		(fp_line
			(start 1.524 -0.762)
			(end -1.524 -0.762)
			(stroke
				(width 0.1524)
				(type default)
			)
			(layer "B.SilkS")
		)
		(fp_line
			(start -1.1049 0.724916)
			(end -1.1049 -0.724916)
			(stroke
				(width 0.1)
				(type default)
			)
			(layer "B.Fab")
		)
		(fp_line
			(start 1.1049 0.724916)
			(end -1.1049 0.724916)
			(stroke
				(width 0.1)
				(type default)
			)
			(layer "B.Fab")
		)
		(fp_line
			(start -1.1049 -0.724916)
			(end 1.1049 -0.724916)
			(stroke
				(width 0.1)
				(type default)
			)
			(layer "B.Fab")
		)
		(fp_line
			(start 1.1049 -0.724916)
			(end 1.1049 0.724916)
			(stroke
				(width 0.1)
				(type default)
			)
			(layer "B.Fab")
		)
		(pad "1" smd rect
			(at 0.889 0 270)
			(size 1.016 1.27)
			(layers "B.Cu" "B.Mask" "B.Paste")
			(net "P3V3_AUX")
		)
		(pad "2" smd rect
			(at -0.889 0 270)
			(size 1.016 1.27)
			(layers "B.Cu" "B.Mask" "B.Paste")
			(net "GND")
		)
	)
	(footprint ""
		(layer "B.Cu")
		(at 177.977546 -321.554856 -90)
		(property "Reference" "C85"
			(at 0 0 90)
			(layer "B.SilkS")
			(hide yes)
			(effects
				(font
					(size 1.27 1.27)
				)
				(justify mirror)
			)
		)
		(property "Value" ""
			(at 0 0 90)
			(layer "B.Fab")
			(effects
				(font
					(size 1.27 1.27)
				)
				(justify mirror)
			)
		)
		(duplicate_pad_numbers_are_jumpers no)
		(fp_line
			(start -1.524 0.762)
			(end 1.524 0.762)
			(stroke
				(width 0.1524)
				(type default)
			)
			(layer "B.SilkS")
		)
		(fp_line
			(start 1.524 0.762)
			(end 1.524 -0.762)
			(stroke
				(width 0.1524)
				(type default)
			)
			(layer "B.SilkS")
		)
		(fp_line
			(start -1.524 -0.762)
			(end -1.524 0.762)
			(stroke
				(width 0.1524)
				(type default)
			)
			(layer "B.SilkS")
		)
		(fp_line
			(start 1.524 -0.762)
			(end -1.524 -0.762)
			(stroke
				(width 0.1524)
				(type default)
			)
			(layer "B.SilkS")
		)
		(fp_line
			(start -1.1049 0.724916)
			(end -1.1049 -0.724916)
			(stroke
				(width 0.1)
				(type default)
			)
			(layer "B.Fab")
		)
		(fp_line
			(start 1.1049 0.724916)
			(end -1.1049 0.724916)
			(stroke
				(width 0.1)
				(type default)
			)
			(layer "B.Fab")
		)
		(fp_line
			(start -1.1049 -0.724916)
			(end 1.1049 -0.724916)
			(stroke
				(width 0.1)
				(type default)
			)
			(layer "B.Fab")
		)
		(fp_line
			(start 1.1049 -0.724916)
			(end 1.1049 0.724916)
			(stroke
				(width 0.1)
				(type default)
			)
			(layer "B.Fab")
		)
		(pad "1" smd rect
			(at 0.889 0 270)
			(size 1.016 1.27)
			(layers "B.Cu" "B.Mask" "B.Paste")
			(net "P12V_S3_AUX_CPU1_NVDIMM")
		)
		(pad "2" smd rect
			(at -0.889 0 270)
			(size 1.016 1.27)
			(layers "B.Cu" "B.Mask" "B.Paste")
			(net "GND")
		)
	)
	(footprint ""
		(layer "B.Cu")
		(at 197.19036 -120.614948)
		(property "Reference" "R1541"
			(at 0 0 0)
			(layer "B.SilkS")
			(hide yes)
			(effects
				(font
					(size 1.27 1.27)
				)
				(justify mirror)
			)
		)
		(property "Value" ""
			(at 0 0 0)
			(layer "B.Fab")
			(effects
				(font
					(size 1.27 1.27)
				)
				(justify mirror)
			)
		)
		(duplicate_pad_numbers_are_jumpers no)
		(fp_line
			(start -0.7874 -0.4064)
			(end -0.7874 0.4064)
			(stroke
				(width 0.1524)
				(type default)
			)
			(layer "B.SilkS")
		)
		(fp_line
			(start -0.7874 0.4064)
			(end 0.7874 0.4064)
			(stroke
				(width 0.1524)
				(type default)
			)
			(layer "B.SilkS")
		)
		(fp_line
			(start 0.7874 -0.4064)
			(end -0.7874 -0.4064)
			(stroke
				(width 0.1524)
				(type default)
			)
			(layer "B.SilkS")
		)
		(fp_line
			(start 0.7874 0.4064)
			(end 0.7874 -0.4064)
			(stroke
				(width 0.1524)
				(type default)
			)
			(layer "B.SilkS")
		)
		(fp_line
			(start -0.67945 -0.3048)
			(end -0.67945 0.3048)
			(stroke
				(width 0.1)
				(type default)
			)
			(layer "B.Fab")
		)
		(fp_line
			(start -0.67945 0.3048)
			(end -0.120396 0.3048)
			(stroke
				(width 0.1)
				(type default)
			)
			(layer "B.Fab")
		)
		(fp_line
			(start -0.12065 -0.3048)
			(end -0.67945 -0.3048)
			(stroke
				(width 0.1)
				(type default)
			)
			(layer "B.Fab")
		)
		(fp_line
			(start -0.12065 -0.2794)
			(end -0.12065 -0.3048)
			(stroke
				(width 0.1)
				(type default)
			)
			(layer "B.Fab")
		)
		(fp_line
			(start -0.120396 0.2794)
			(end 0.12065 0.2794)
			(stroke
				(width 0.1)
				(type default)
			)
			(layer "B.Fab")
		)
		(fp_line
			(start -0.120396 0.3048)
			(end -0.120396 0.2794)
			(stroke
				(width 0.1)
				(type default)
			)
			(layer "B.Fab")
		)
		(fp_line
			(start 0.12065 -0.305054)
			(end 0.12065 -0.2794)
			(stroke
				(width 0.1)
				(type default)
			)
			(layer "B.Fab")
		)
		(fp_line
			(start 0.12065 -0.2794)
			(end -0.12065 -0.2794)
			(stroke
				(width 0.1)
				(type default)
			)
			(layer "B.Fab")
		)
		(fp_line
			(start 0.12065 0.2794)
			(end 0.12065 0.3048)
			(stroke
				(width 0.1)
				(type default)
			)
			(layer "B.Fab")
		)
		(fp_line
			(start 0.12065 0.3048)
			(end 0.67945 0.3048)
			(stroke
				(width 0.1)
				(type default)
			)
			(layer "B.Fab")
		)
		(fp_line
			(start 0.67945 -0.305054)
			(end 0.12065 -0.305054)
			(stroke
				(width 0.1)
				(type default)
			)
			(layer "B.Fab")
		)
		(fp_line
			(start 0.67945 0.3048)
			(end 0.67945 -0.305054)
			(stroke
				(width 0.1)
				(type default)
			)
			(layer "B.Fab")
		)
		(pad "1" smd circle
			(at 0.40005 0 180)
			(size 0 0)
			(layers "B.Cu" "B.Mask" "B.Paste")
			(net "GND")
		)
		(pad "2" smd circle
			(at -0.40005 0 180)
			(size 0 0)
			(layers "B.Cu" "B.Mask" "B.Paste")
			(net "RST_PLTRST_N")
		)
	)
	(footprint ""
		(layer "B.Cu")
		(at 277.868888 -317.857886 180)
		(property "Reference" "R3880"
			(at 0 0 0)
			(layer "B.SilkS")
			(hide yes)
			(effects
				(font
					(size 1.27 1.27)
				)
				(justify mirror)
			)
		)
		(property "Value" ""
			(at 0 0 0)
			(layer "B.Fab")
			(effects
				(font
					(size 1.27 1.27)
				)
				(justify mirror)
			)
		)
		(duplicate_pad_numbers_are_jumpers no)
		(fp_line
			(start 0.7874 0.4064)
			(end 0.7874 -0.4064)
			(stroke
				(width 0.1524)
				(type default)
			)
			(layer "B.SilkS")
		)
		(fp_line
			(start 0.7874 -0.4064)
			(end -0.7874 -0.4064)
			(stroke
				(width 0.1524)
				(type default)
			)
			(layer "B.SilkS")
		)
		(fp_line
			(start -0.7874 0.4064)
			(end 0.7874 0.4064)
			(stroke
				(width 0.1524)
				(type default)
			)
			(layer "B.SilkS")
		)
		(fp_line
			(start -0.7874 -0.4064)
			(end -0.7874 0.4064)
			(stroke
				(width 0.1524)
				(type default)
			)
			(layer "B.SilkS")
		)
		(fp_line
			(start 0.67945 0.3048)
			(end 0.67945 -0.305054)
			(stroke
				(width 0.1)
				(type default)
			)
			(layer "B.Fab")
		)
		(fp_line
			(start 0.67945 -0.305054)
			(end 0.12065 -0.305054)
			(stroke
				(width 0.1)
				(type default)
			)
			(layer "B.Fab")
		)
		(fp_line
			(start 0.12065 0.3048)
			(end 0.67945 0.3048)
			(stroke
				(width 0.1)
				(type default)
			)
			(layer "B.Fab")
		)
		(fp_line
			(start 0.12065 0.2794)
			(end 0.12065 0.3048)
			(stroke
				(width 0.1)
				(type default)
			)
			(layer "B.Fab")
		)
		(fp_line
			(start 0.12065 -0.2794)
			(end -0.12065 -0.2794)
			(stroke
				(width 0.1)
				(type default)
			)
			(layer "B.Fab")
		)
		(fp_line
			(start 0.12065 -0.305054)
			(end 0.12065 -0.2794)
			(stroke
				(width 0.1)
				(type default)
			)
			(layer "B.Fab")
		)
		(fp_line
			(start -0.120396 0.3048)
			(end -0.120396 0.2794)
			(stroke
				(width 0.1)
				(type default)
			)
			(layer "B.Fab")
		)
		(fp_line
			(start -0.120396 0.2794)
			(end 0.12065 0.2794)
			(stroke
				(width 0.1)
				(type default)
			)
			(layer "B.Fab")
		)
		(fp_line
			(start -0.12065 -0.2794)
			(end -0.12065 -0.3048)
			(stroke
				(width 0.1)
				(type default)
			)
			(layer "B.Fab")
		)
		(fp_line
			(start -0.12065 -0.3048)
			(end -0.67945 -0.3048)
			(stroke
				(width 0.1)
				(type default)
			)
			(layer "B.Fab")
		)
		(fp_line
			(start -0.67945 0.3048)
			(end -0.120396 0.3048)
			(stroke
				(width 0.1)
				(type default)
			)
			(layer "B.Fab")
		)
		(fp_line
			(start -0.67945 -0.3048)
			(end -0.67945 0.3048)
			(stroke
				(width 0.1)
				(type default)
			)
			(layer "B.Fab")
		)
		(pad "1" smd circle
			(at 0.40005 0)
			(size 0 0)
			(layers "B.Cu" "B.Mask" "B.Paste")
			(net "I3C_SPD_DDRABCD_CPU0_LVC1_SCL_5")
		)
		(pad "2" smd circle
			(at -0.40005 0)
			(size 0 0)
			(layers "B.Cu" "B.Mask" "B.Paste")
			(net "I3C_SPD_DDRABCD_CPU0_LVC1_SCL")
		)
	)
)
